FILE_TYPE = CONNECTIVITY;
{Allegro Design Entry HDL 17.4-2019 S026 (4007227) 1/17/2022}
"PAGE_NUMBER" = 248;
0"NC";
1"GND\g";
2"GND\g";
3"GND\g";
4"GND\g";
5"SMB_OCP_V3_2_3V3AUX_BUF_SCL"CDS_PHYS_NET_NAME"SMB_OCP_V3_2_3V3AUX_BUF_SCL";
6"P3V3_OCP_V3_2\g";
7"SMB_OCP_V3_2_3V3AUX_BUF_SDA"CDS_PHYS_NET_NAME"SMB_OCP_V3_2_3V3AUX_BUF_SDA";
8"P3V3_OCP_V3_2_EN_R"$PHYS_NET_NAME"RST_PCIE_M2_N"CDS_PHYS_NET_NAME"HP_LVC3_OCP_V3_2_EN";
9"HP_LVC3_OCP_V3_2_P12V_PWRGD";
10"HP_LVC3_OCP_V3_1_P12V_PWRGD";
11"P12V_OCP_V3_2_BUF_EN_R";
12"P12V_OCP_SFF_BUF_EN_R";
13"P3V3_OCP_V3_2\g";
14"HP_LVC3_OCP_V3_2_R_EN"CDS_PHYS_NET_NAME"HP_LVC3_OCP_V3_2_R_EN"$PHYS_NET_NAME"RST_PCIE_M2_N";
15"GND\g";
16"P3V3_AUX\g";
17"P3V3_OCP_SFF\g";
18"P3V3_OCP_SFF\g";
19"GND\g";
20"P3V3_AUX\g";
21"SMB_OCP_SFF_3V3AUX_BUF_SCL"CDS_PHYS_NET_NAME"SMB_OCP_SFF_3V3AUX_BUF_SCL";
22"P3V3_OCP_SFF_EN_R"$PHYS_NET_NAME"RST_PCIE_M2_N"CDS_PHYS_NET_NAME"HP_LVC3_OCP_V3_1_EN";
23"SMB_OCP_SFF_3V3AUX_BUF_SDA"CDS_PHYS_NET_NAME"SMB_OCP_SFF_3V3AUX_BUF_SDA";
24"HP_LVC3_OCP_V3_1_R_EN"$PHYS_NET_NAME"RST_PCIE_M2_N"CDS_PHYS_NET_NAME"HP_LVC3_OCP_V3_1_R_EN";
25"SMB_OCP_V3_2_3V3AUX_SCL"CDS_PHYS_NET_NAME"SMB_OCP_V3_2_3V3AUX_SCL";
26"SMB_OCP_SFF_3V3AUX_SCL"CDS_PHYS_NET_NAME"SMB_OCP_SFF_3V3AUX_SCL";
27"SMB_OCP_SFF_3V3AUX_SDA"CDS_PHYS_NET_NAME"SMB_OCP_SFF_3V3AUX_SDA";
28"SMB_OCP_V3_2_3V3AUX_SDA"CDS_PHYS_NET_NAME"SMB_OCP_V3_2_3V3AUX_SDA";
%"UNIVERSAL_POWER"
"1","(-4225,3975)","0","pure_quanta_power","I10";
;
HDL_POWER"P3V3_OCP_V3_2"
CDS_LIB"pure_quanta_power";
"A"13;
%"UNIVERSAL_GND"
"1","(-5275,4625)","0","pure_quanta_power","I13";
;
CDS_LIB"pure_quanta_power"
HDL_POWER"GND";
"A"15;
%"PCA9617ADP"
"1","(-4750,5050)","0","pure_quanta","I14";
;
LOCATION"U236"
$SEC"1"
CDS_SEC"1"
PART_TYPE"SMLF"
VALUE"PCA9617ADP"
MATERIAL"IC"
NEEDS_NO_SIZE"TRUE"
CDS_LMAN_SYM_OUTLINE"-275,300,275,-300"
CDS_LIB"pure_quanta"
PART_NUMBER"AL009617K02";
"GND"
$PN"4"15;
"SCLB"
$PN"7"21;
"SDAB"
$PN"6"23;
"SDAA"
$PN"3"27;
"SCLA"
$PN"2"26;
"VCCB"
$PN"8"17;
"VCCA"
$PN"1"16;
"EN"
$PN"5"24;
%"Q_CAP"
"1","(-5675,5500)","0","pure_quanta","I15";
;
LOCATION"C1860"
$SEC"1"
CDS_SEC"1"
VALUE"0.1UF"
TOLERANCE"10%"
MATERIAL"X7R"
VOLTAGE"25V"
PACK_TYPE"0402"
CDS_LIB"pure_quanta"
PART_NUMBER"CH4104K1B00";
"B"
$PN"2"1;
"A"
$PN"1"16;
%"UNIVERSAL_GND"
"1","(-5675,5275)","0","pure_quanta_power","I16";
;
CDS_LIB"pure_quanta_power"
HDL_POWER"GND";
"A"1;
%"UNIVERSAL_POWER"
"1","(-5325,5800)","0","pure_quanta_power","I17";
;
HDL_POWER"P3V3_AUX"
CDS_LIB"pure_quanta_power";
"A"16;
%"UNIVERSAL_POWER"
"1","(-4200,5800)","0","pure_quanta_power","I18";
;
HDL_POWER"P3V3_OCP_SFF"
CDS_LIB"pure_quanta_power";
"A"17;
%"Q_CAP"
"1","(-4000,5500)","0","pure_quanta","I19";
;
LOCATION"C1862"
$SEC"1"
CDS_SEC"1"
TOLERANCE"10%"
VALUE"0.1UF"
VOLTAGE"25V"
PACK_TYPE"0402"
MATERIAL"X7R"
CDS_LIB"pure_quanta"
PART_NUMBER"CH4104K1B00";
"B"
$PN"2"2;
"A"
$PN"1"17;
%"UNIVERSAL_GND"
"1","(-4000,5300)","0","pure_quanta_power","I20";
;
CDS_LIB"pure_quanta_power"
HDL_POWER"GND";
"A"2;
%"UNIVERSAL_POWER"
"1","(-3200,3950)","0","pure_quanta_power","I22";
;
HDL_POWER"P3V3_OCP_V3_2"
CDS_LIB"pure_quanta_power";
"A"6;
%"Q_RES"
"2","(-2950,3625)","0","pure_quanta","I23";
;
LOCATION"R3520"
$SEC"1"
CDS_SEC"1"
PACK_TYPE"0402LF"
MATERIAL"CHIP"
WATTAGE"1/16W"
TOLERANCE"5%"
VALUE"4.7K"
CDS_LIB"pure_quanta"
PART_NUMBER"CS24702JB10";
"A"
$PN"1"6;
"B"
$PN"2"7;
%"Q_RES"
"2","(-3025,5450)","0","pure_quanta","I27";
;
LOCATION"R3500"
$SEC"1"
CDS_SEC"1"
PACK_TYPE"0402LF"
MATERIAL"CHIP"
VALUE"4.7K"
TOLERANCE"5%"
WATTAGE"1/16W"
CDS_LIB"pure_quanta"
PART_NUMBER"CS24702JB10";
"A"
$PN"1"18;
"B"
$PN"2"21;
%"UNIVERSAL_POWER"
"1","(-3025,5775)","0","pure_quanta_power","I28";
;
HDL_POWER"P3V3_OCP_SFF"
CDS_LIB"pure_quanta_power";
"A"18;
%"UNIVERSAL_GND"
"1","(-5300,2800)","0","pure_quanta_power","I3";
;
CDS_LIB"pure_quanta_power"
HDL_POWER"GND";
"A"19;
%"Q_RES"
"2","(-2775,5450)","0","pure_quanta","I31";
;
LOCATION"R3501"
$SEC"1"
CDS_SEC"1"
MATERIAL"CHIP"
PACK_TYPE"0402LF"
WATTAGE"1/16W"
TOLERANCE"5%"
VALUE"4.7K"
CDS_LIB"pure_quanta"
PART_NUMBER"CS24702JB10";
"A"
$PN"1"18;
"B"
$PN"2"23;
%"Q_RES"
"2","(-3200,3625)","0","pure_quanta","I34";
;
LOCATION"R3519"
$SEC"1"
CDS_SEC"1"
VALUE"4.7K"
TOLERANCE"5%"
WATTAGE"1/16W"
MATERIAL"CHIP"
PACK_TYPE"0402LF"
CDS_LIB"pure_quanta"
PART_NUMBER"CS24702JB10";
"A"
$PN"1"6;
"B"
$PN"2"5;
%"Q_RES"
"1","(-3450,4850)","0","pure_quanta","I35";
;
LOCATION"R3263"
$SEC"1"
CDS_SEC"1"
TOLERANCE"5%"
VALUE"0"
PACK_TYPE"0402LF"
MATERIAL"EMPTY"
CDS_LIB"pure_quanta"
WATTAGE"1/16W"
PART_NUMBER"CS00002JB13";
"B"
$PN"2"22;
"A"
$PN"1"24;
%"Q_RES"
"1","(-3375,3025)","0","pure_quanta","I38";
;
LOCATION"R3264"
$SEC"1"
CDS_SEC"1"
MATERIAL"EMPTY"
TOLERANCE"5%"
VALUE"0"
WATTAGE"1/16W"
PACK_TYPE"0402LF"
CDS_LIB"pure_quanta"
PART_NUMBER"CS00002JB13";
"B"
$PN"2"8;
"A"
$PN"1"14;
%"Q_CAP"
"1","(-5700,3675)","0","pure_quanta","I4";
;
LOCATION"C1859"
$SEC"1"
CDS_SEC"1"
VALUE"0.1UF"
VOLTAGE"25V"
MATERIAL"X7R"
PACK_TYPE"0402"
TOLERANCE"10%"
CDS_LIB"pure_quanta"
PART_NUMBER"CH4104K1B00";
"B"
$PN"2"3;
"A"
$PN"1"20;
%"Q_RES"
"1","(-3450,4650)","0","pure_quanta","I41";
;
LOCATION"R1135"
$SEC"1"
CDS_SEC"1"
PACK_TYPE"0402LF"
TOLERANCE"5%"
MATERIAL"EMPTY"
VALUE"0"
CDS_LIB"pure_quanta"
WATTAGE"1/16W"
PART_NUMBER"CS00002JB13";
"B"
$PN"2"10;
"A"
$PN"1"24;
%"Q_RES"
"1","(-3450,4475)","0","pure_quanta","I43";
;
LOCATION"R1500"
$SEC"1"
CDS_SEC"1"
TOLERANCE"5%"
MATERIAL"CHIP"
VALUE"0"
PACK_TYPE"0402LF"
WATTAGE"1/16W"
CDS_LIB"pure_quanta"
PART_NUMBER"CS00002JB13";
"B"
$PN"2"12;
"A"
$PN"1"24;
%"Q_RES"
"1","(-3350,2600)","0","pure_quanta","I44";
;
LOCATION"R1522"
$SEC"1"
CDS_SEC"1"
MATERIAL"CHIP"
VALUE"0"
TOLERANCE"5%"
CDS_LIB"pure_quanta"
PACK_TYPE"0402LF"
WATTAGE"1/16W"
PART_NUMBER"CS00002JB13";
"B"
$PN"2"11;
"A"
$PN"1"14;
%"Q_RES"
"1","(-3350,2850)","0","pure_quanta","I45";
;
LOCATION"R1180"
$SEC"1"
CDS_SEC"1"
VALUE"0"
TOLERANCE"5%"
MATERIAL"EMPTY"
CDS_LIB"pure_quanta"
WATTAGE"1/16W"
PACK_TYPE"0402LF"
PART_NUMBER"CS00002JB13";
"B"
$PN"2"9;
"A"
$PN"1"14;
%"UNIVERSAL_GND"
"1","(-5700,3450)","0","pure_quanta_power","I5";
;
CDS_LIB"pure_quanta_power"
HDL_POWER"GND";
"A"3;
%"PCA9617ADP"
"1","(-4775,3225)","0","pure_quanta","I6";
;
LOCATION"U235"
$SEC"1"
CDS_SEC"1"
MATERIAL"IC"
PART_TYPE"SMLF"
VALUE"PCA9617ADP"
CDS_LIB"pure_quanta"
CDS_LMAN_SYM_OUTLINE"-275,300,275,-300"
NEEDS_NO_SIZE"TRUE"
PART_NUMBER"AL009617K02";
"GND"
$PN"4"19;
"SCLB"
$PN"7"5;
"SDAB"
$PN"6"7;
"SDAA"
$PN"3"28;
"SCLA"
$PN"2"25;
"VCCB"
$PN"8"13;
"VCCA"
$PN"1"20;
"EN"
$PN"5"14;
%"UNIVERSAL_POWER"
"1","(-5350,3975)","0","pure_quanta_power","I7";
;
HDL_POWER"P3V3_AUX"
CDS_LIB"pure_quanta_power";
"A"20;
%"UNIVERSAL_GND"
"1","(-4025,3475)","0","pure_quanta_power","I8";
;
CDS_LIB"pure_quanta_power"
HDL_POWER"GND";
"A"4;
%"Q_CAP"
"1","(-4025,3675)","0","pure_quanta","I9";
;
LOCATION"C1861"
$SEC"1"
CDS_SEC"1"
VOLTAGE"25V"
VALUE"0.1UF"
TOLERANCE"10%"
PACK_TYPE"0402"
MATERIAL"X7R"
CDS_LIB"pure_quanta"
PART_NUMBER"CH4104K1B00";
"B"
$PN"2"4;
"A"
$PN"1"13;
END.
